(kicad_pcb
	(version 20260206)
	(generator "pcbnew")
	(generator_version "10.0")
	(general
		(thickness 1.6)
		(legacy_teardrops no)
	)
	(paper "A4")
	(title_block
		(title "01162023_DA0F0TEBIF0_F0T_Expander_BD_F_brd_V02_OCP.brd")
		(comment 1 "Grand Teton / footprints 7769-7775 of 9728")
	)
	(layers
		(0 "F.Cu" signal "TOP")
		(4 "In1.Cu" signal "GND")
		(6 "In2.Cu" signal "VCC")
		(8 "In3.Cu" signal "VCC1")
		(10 "In4.Cu" signal "GND1")
		(12 "In5.Cu" signal "IN1")
		(14 "In6.Cu" signal "GND2")
		(16 "In7.Cu" signal "IN2")
		(18 "In8.Cu" signal "GND3")
		(20 "In9.Cu" signal "IN3")
		(22 "In10.Cu" signal "GND4")
		(24 "In11.Cu" signal "IN4")
		(26 "In12.Cu" signal "GND5")
		(28 "In13.Cu" signal "IN5")
		(30 "In14.Cu" signal "GND6")
		(32 "In15.Cu" signal "IN6")
		(34 "In16.Cu" signal "GND7")
		(2 "B.Cu" signal "BOTTOM")
		(9 "F.Adhes" user "F.Adhesive")
		(11 "B.Adhes" user "B.Adhesive")
		(13 "F.Paste" user "Package Geometry/Pastemask Top")
		(15 "B.Paste" user "Package Geometry/Pastemask Bottom")
		(5 "F.SilkS" user "Ref Des/Silkscreen Top")
		(7 "B.SilkS" user "Ref Des/Silkscreen Bottom")
		(1 "F.Mask" user "Board Geometry/Soldermask Top")
		(3 "B.Mask" user "Board Geometry/Soldermask Bottom")
		(17 "Dwgs.User" user "User.Drawings")
		(19 "Cmts.User" user "User.Comments")
		(21 "Eco1.User" user "User.Eco1")
		(23 "Eco2.User" user "User.Eco2")
		(25 "Edge.Cuts" user "Board Geometry/Outline")
		(27 "Margin" user)
		(31 "F.CrtYd" user "Package Geometry/Place Bound Top")
		(29 "B.CrtYd" user "Package Geometry/Place Bound Bottom")
		(35 "F.Fab" user "Ref Des/Assembly Top")
		(33 "B.Fab" user "Ref Des/Assembly Bottom")
	)
	(footprint ""
		(layer "B.Cu")
		(at 219.519246 -223.251268)
		(property "Reference" "R6803"
			(at 0 0 0)
			(layer "B.SilkS")
			(hide yes)
			(effects
				(font
					(size 1.27 1.27)
				)
				(justify mirror)
			)
		)
		(property "Value" ""
			(at 0 0 0)
			(layer "B.Fab")
			(effects
				(font
					(size 1.27 1.27)
				)
				(justify mirror)
			)
		)
		(duplicate_pad_numbers_are_jumpers no)
		(fp_line
			(start -0.7874 -0.4064)
			(end -0.7874 0.4064)
			(stroke
				(width 0.1524)
				(type default)
			)
			(layer "B.SilkS")
		)
		(fp_line
			(start -0.7874 0.4064)
			(end 0.7874 0.4064)
			(stroke
				(width 0.1524)
				(type default)
			)
			(layer "B.SilkS")
		)
		(fp_line
			(start 0.7874 -0.4064)
			(end -0.7874 -0.4064)
			(stroke
				(width 0.1524)
				(type default)
			)
			(layer "B.SilkS")
		)
		(fp_line
			(start 0.7874 0.4064)
			(end 0.7874 -0.4064)
			(stroke
				(width 0.1524)
				(type default)
			)
			(layer "B.SilkS")
		)
		(fp_line
			(start -0.67945 -0.3048)
			(end -0.67945 0.3048)
			(stroke
				(width 0.1)
				(type default)
			)
			(layer "B.Fab")
		)
		(fp_line
			(start -0.67945 0.3048)
			(end -0.120396 0.3048)
			(stroke
				(width 0.1)
				(type default)
			)
			(layer "B.Fab")
		)
		(fp_line
			(start -0.12065 -0.3048)
			(end -0.67945 -0.3048)
			(stroke
				(width 0.1)
				(type default)
			)
			(layer "B.Fab")
		)
		(fp_line
			(start -0.12065 -0.2794)
			(end -0.12065 -0.3048)
			(stroke
				(width 0.1)
				(type default)
			)
			(layer "B.Fab")
		)
		(fp_line
			(start -0.120396 0.2794)
			(end 0.12065 0.2794)
			(stroke
				(width 0.1)
				(type default)
			)
			(layer "B.Fab")
		)
		(fp_line
			(start -0.120396 0.3048)
			(end -0.120396 0.2794)
			(stroke
				(width 0.1)
				(type default)
			)
			(layer "B.Fab")
		)
		(fp_line
			(start 0.12065 -0.305054)
			(end 0.12065 -0.2794)
			(stroke
				(width 0.1)
				(type default)
			)
			(layer "B.Fab")
		)
		(fp_line
			(start 0.12065 -0.2794)
			(end -0.12065 -0.2794)
			(stroke
				(width 0.1)
				(type default)
			)
			(layer "B.Fab")
		)
		(fp_line
			(start 0.12065 0.2794)
			(end 0.12065 0.3048)
			(stroke
				(width 0.1)
				(type default)
			)
			(layer "B.Fab")
		)
		(fp_line
			(start 0.12065 0.3048)
			(end 0.67945 0.3048)
			(stroke
				(width 0.1)
				(type default)
			)
			(layer "B.Fab")
		)
		(fp_line
			(start 0.67945 -0.305054)
			(end 0.12065 -0.305054)
			(stroke
				(width 0.1)
				(type default)
			)
			(layer "B.Fab")
		)
		(fp_line
			(start 0.67945 0.3048)
			(end 0.67945 -0.305054)
			(stroke
				(width 0.1)
				(type default)
			)
			(layer "B.Fab")
		)
		(pad "1" smd circle
			(at 0.40005 0 180)
			(size 0 0)
			(layers "B.Cu" "B.Mask" "B.Paste")
			(net "SMB_BIC_FPGA_R2_SDA")
		)
		(pad "2" smd circle
			(at -0.40005 0 180)
			(size 0 0)
			(layers "B.Cu" "B.Mask" "B.Paste")
			(net "SMB_BIC_FPGA_SDA")
		)
	)
	(footprint ""
		(layer "B.Cu")
		(at 125.872748 -204.342238 180)
		(property "Reference" "U99"
			(at 0.119888 2.274062 0)
			(unlocked yes)
			(layer "B.SilkS")
			(effects
				(font
					(size 0.7874 0.5842)
					(thickness 0.1524)
				)
				(justify mirror)
			)
		)
		(property "Value" ""
			(at 0 0 0)
			(layer "B.Fab")
			(effects
				(font
					(size 1.27 1.27)
				)
				(justify mirror)
			)
		)
		(duplicate_pad_numbers_are_jumpers no)
		(fp_line
			(start 2.085848 1.549908)
			(end 2.085848 -1.549908)
			(stroke
				(width 0.1524)
				(type default)
			)
			(layer "B.SilkS")
		)
		(fp_line
			(start 2.085848 -1.549908)
			(end 0.695198 -1.549908)
			(stroke
				(width 0.1524)
				(type default)
			)
			(layer "B.SilkS")
		)
		(fp_line
			(start 0.695198 -1.549908)
			(end 0 -0.85471)
			(stroke
				(width 0.1524)
				(type default)
			)
			(layer "B.SilkS")
		)
		(fp_line
			(start 0 -0.85471)
			(end -0.695198 -1.549908)
			(stroke
				(width 0.1524)
				(type default)
			)
			(layer "B.SilkS")
		)
		(fp_line
			(start -0.695198 -1.549908)
			(end -2.085848 -1.549908)
			(stroke
				(width 0.1524)
				(type default)
			)
			(layer "B.SilkS")
		)
		(fp_line
			(start -2.085848 1.549908)
			(end 2.085848 1.549908)
			(stroke
				(width 0.1524)
				(type default)
			)
			(layer "B.SilkS")
		)
		(fp_line
			(start -2.085848 -1.549908)
			(end -2.085848 1.549908)
			(stroke
				(width 0.1524)
				(type default)
			)
			(layer "B.SilkS")
		)
		(fp_poly
			(pts
				(xy 3.432048 -1.45796) (xy 3.432048 -0.44196) (xy 2.416048 -0.94996)
			)
			(stroke
				(width 0)
				(type default)
			)
			(fill yes)
			(layer "B.SilkS")
		)
		(fp_line
			(start 0.899922 1.549908)
			(end 0.899922 -1.549908)
			(stroke
				(width 0.1)
				(type default)
			)
			(layer "B.Fab")
		)
		(fp_line
			(start 0.899922 -1.549908)
			(end -0.899922 -1.549908)
			(stroke
				(width 0.1)
				(type default)
			)
			(layer "B.Fab")
		)
		(fp_line
			(start -0.899922 1.549908)
			(end 0.899922 1.549908)
			(stroke
				(width 0.1)
				(type default)
			)
			(layer "B.Fab")
		)
		(fp_line
			(start -0.899922 -1.549908)
			(end -0.899922 1.549908)
			(stroke
				(width 0.1)
				(type default)
			)
			(layer "B.Fab")
		)
		(fp_poly
			(pts
				(xy 3.432048 -1.45796) (xy 3.432048 -0.44196) (xy 2.416048 -0.94996)
			)
			(stroke
				(width 0)
				(type default)
			)
			(fill yes)
			(layer "B.Fab")
		)
		(pad "1" smd rect
			(at 1.400048 -0.94996 90)
			(size 0.6096 1.1176)
			(layers "B.Cu" "B.Mask" "B.Paste")
			(net "FT4232_CLI_EEPROM_DO")
		)
		(pad "2" smd rect
			(at 1.400048 0 90)
			(size 0.6096 1.1176)
			(layers "B.Cu" "B.Mask" "B.Paste")
			(net "GND")
		)
		(pad "3" smd rect
			(at 1.400048 0.94996 90)
			(size 0.6096 1.1176)
			(layers "B.Cu" "B.Mask" "B.Paste")
			(net "FT4232_CLI_EEPROM_R_SDA")
		)
		(pad "4" smd rect
			(at -1.400048 0.94996 90)
			(size 0.6096 1.1176)
			(layers "B.Cu" "B.Mask" "B.Paste")
			(net "FT4232_CLI_EEPROM_R_SCL")
		)
		(pad "5" smd rect
			(at -1.400048 0 90)
			(size 0.6096 1.1176)
			(layers "B.Cu" "B.Mask" "B.Paste")
			(net "FT4232_CLI_EEPROM_R_CS")
		)
		(pad "6" smd rect
			(at -1.400048 -0.94996 90)
			(size 0.6096 1.1176)
			(layers "B.Cu" "B.Mask" "B.Paste")
			(net "P3V3_AUX")
		)
	)
	(footprint ""
		(layer "B.Cu")
		(at 177.858166 -296.37482)
		(property "Reference" "C1374"
			(at 0 0 0)
			(layer "B.SilkS")
			(hide yes)
			(effects
				(font
					(size 1.27 1.27)
				)
				(justify mirror)
			)
		)
		(property "Value" ""
			(at 0 0 0)
			(layer "B.Fab")
			(effects
				(font
					(size 1.27 1.27)
				)
				(justify mirror)
			)
		)
		(duplicate_pad_numbers_are_jumpers no)
		(fp_line
			(start -0.299974 -0.150114)
			(end -0.299974 0.150114)
			(stroke
				(width 0.1)
				(type default)
			)
			(layer "B.Fab")
		)
		(fp_line
			(start -0.299974 0.150114)
			(end 0.299974 0.150114)
			(stroke
				(width 0.1)
				(type default)
			)
			(layer "B.Fab")
		)
		(fp_line
			(start 0.299974 -0.150114)
			(end -0.299974 -0.150114)
			(stroke
				(width 0.1)
				(type default)
			)
			(layer "B.Fab")
		)
		(fp_line
			(start 0.299974 0.150114)
			(end 0.299974 -0.150114)
			(stroke
				(width 0.1)
				(type default)
			)
			(layer "B.Fab")
		)
		(pad "1" smd rect
			(at 0.2667 0 180)
			(size 0.3048 0.381)
			(layers "B.Cu" "B.Mask" "B.Paste")
			(net "P0V8_PEX1")
		)
		(pad "2" smd rect
			(at -0.2667 0 180)
			(size 0.3048 0.381)
			(layers "B.Cu" "B.Mask" "B.Paste")
			(net "GND")
		)
	)
	(footprint ""
		(layer "B.Cu")
		(at 401.774914 -297.79976 90)
		(property "Reference" "C1881"
			(at 0 0 90)
			(layer "B.SilkS")
			(hide yes)
			(effects
				(font
					(size 1.27 1.27)
				)
				(justify mirror)
			)
		)
		(property "Value" ""
			(at 0 0 90)
			(layer "B.Fab")
			(effects
				(font
					(size 1.27 1.27)
				)
				(justify mirror)
			)
		)
		(duplicate_pad_numbers_are_jumpers no)
		(fp_line
			(start 0.299974 -0.150114)
			(end -0.299974 -0.150114)
			(stroke
				(width 0.1)
				(type default)
			)
			(layer "B.Fab")
		)
		(fp_line
			(start -0.299974 -0.150114)
			(end -0.299974 0.150114)
			(stroke
				(width 0.1)
				(type default)
			)
			(layer "B.Fab")
		)
		(fp_line
			(start 0.299974 0.150114)
			(end 0.299974 -0.150114)
			(stroke
				(width 0.1)
				(type default)
			)
			(layer "B.Fab")
		)
		(fp_line
			(start -0.299974 0.150114)
			(end 0.299974 0.150114)
			(stroke
				(width 0.1)
				(type default)
			)
			(layer "B.Fab")
		)
		(pad "1" smd rect
			(at 0.2667 0 270)
			(size 0.3048 0.381)
			(layers "B.Cu" "B.Mask" "B.Paste")
			(net "P0V8_PEX3")
		)
		(pad "2" smd rect
			(at -0.2667 0 270)
			(size 0.3048 0.381)
			(layers "B.Cu" "B.Mask" "B.Paste")
			(net "GND")
		)
	)
	(footprint ""
		(layer "B.Cu")
		(at 345.710002 -293.660068 90)
		(property "Reference" "PC151"
			(at 0 0 90)
			(layer "B.SilkS")
			(hide yes)
			(effects
				(font
					(size 1.27 1.27)
				)
				(justify mirror)
			)
		)
		(property "Value" ""
			(at 0 0 90)
			(layer "B.Fab")
			(effects
				(font
					(size 1.27 1.27)
				)
				(justify mirror)
			)
		)
		(duplicate_pad_numbers_are_jumpers no)
		(fp_line
			(start 4.84378 -2.150618)
			(end 4.53898 -2.150618)
			(stroke
				(width 0.1524)
				(type default)
			)
			(layer "B.SilkS")
		)
		(fp_line
			(start 4.84378 -2.150618)
			(end 4.842256 2.163064)
			(stroke
				(width 0.1524)
				(type default)
			)
			(layer "B.SilkS")
		)
		(fp_line
			(start 4.69138 -2.150618)
			(end 4.692396 2.161032)
			(stroke
				(width 0.1524)
				(type default)
			)
			(layer "B.SilkS")
		)
		(fp_line
			(start 4.53898 -2.150618)
			(end 4.539742 2.152142)
			(stroke
				(width 0.1524)
				(type default)
			)
			(layer "B.SilkS")
		)
		(fp_line
			(start 4.53898 -2.15011)
			(end -4.53898 -2.15011)
			(stroke
				(width 0.1524)
				(type default)
			)
			(layer "B.SilkS")
		)
		(fp_line
			(start -4.53898 -2.15011)
			(end -4.53898 2.15011)
			(stroke
				(width 0.1524)
				(type default)
			)
			(layer "B.SilkS")
		)
		(fp_line
			(start 4.53898 2.15011)
			(end 4.53898 -2.15011)
			(stroke
				(width 0.1524)
				(type default)
			)
			(layer "B.SilkS")
		)
		(fp_line
			(start -4.53898 2.15011)
			(end 4.53898 2.15011)
			(stroke
				(width 0.1524)
				(type default)
			)
			(layer "B.SilkS")
		)
		(fp_line
			(start 4.83108 2.150364)
			(end 4.447794 2.149348)
			(stroke
				(width 0.1524)
				(type default)
			)
			(layer "B.SilkS")
		)
		(fp_line
			(start 3.64998 -2.15011)
			(end -3.64998 -2.15011)
			(stroke
				(width 0.1)
				(type default)
			)
			(layer "B.Fab")
		)
		(fp_line
			(start -3.64998 -2.15011)
			(end -3.64998 2.15011)
			(stroke
				(width 0.1)
				(type default)
			)
			(layer "B.Fab")
		)
		(fp_line
			(start 3.64998 2.15011)
			(end 3.64998 -2.15011)
			(stroke
				(width 0.1)
				(type default)
			)
			(layer "B.Fab")
		)
		(fp_line
			(start -3.64998 2.15011)
			(end 3.64998 2.15011)
			(stroke
				(width 0.1)
				(type default)
			)
			(layer "B.Fab")
		)
		(fp_text user "+"
			(at 6.214872 -0.337058 90)
			(unlocked yes)
			(layer "B.SilkS")
			(effects
				(font
					(size 1.905 1.4224)
					(thickness 0.1524)
				)
				(justify left mirror)
			)
		)
		(fp_text user "-"
			(at -4.313174 -0.094488 90)
			(unlocked yes)
			(layer "B.SilkS")
			(effects
				(font
					(size 1.905 1.4224)
					(thickness 0.1524)
				)
				(justify left mirror)
			)
		)
		(fp_text user "+"
			(at 6.214872 -0.337058 90)
			(unlocked yes)
			(layer "B.Fab")
			(effects
				(font
					(size 1.905 1.4224)
					(thickness 0.1524)
				)
				(justify left mirror)
			)
		)
		(fp_text user "-"
			(at -4.313174 -0.094488 90)
			(unlocked yes)
			(layer "B.Fab")
			(effects
				(font
					(size 1.905 1.4224)
					(thickness 0.1524)
				)
				(justify left mirror)
			)
		)
		(pad "1" smd rect
			(at 3.199892 0 270)
			(size 2.413 2.8194)
			(layers "B.Cu" "B.Mask" "B.Paste")
			(net "P0V8_PEX2")
		)
		(pad "2" smd rect
			(at -3.199892 0 270)
			(size 2.413 2.8194)
			(layers "B.Cu" "B.Mask" "B.Paste")
			(net "GND")
		)
	)
	(footprint ""
		(layer "B.Cu")
		(at 225.19894 -192.959482 -90)
		(property "Reference" "R1026"
			(at 0 0 90)
			(layer "B.SilkS")
			(hide yes)
			(effects
				(font
					(size 1.27 1.27)
				)
				(justify mirror)
			)
		)
		(property "Value" ""
			(at 0 0 90)
			(layer "B.Fab")
			(effects
				(font
					(size 1.27 1.27)
				)
				(justify mirror)
			)
		)
		(duplicate_pad_numbers_are_jumpers no)
		(fp_line
			(start -0.7874 0.4064)
			(end 0.7874 0.4064)
			(stroke
				(width 0.1524)
				(type default)
			)
			(layer "B.SilkS")
		)
		(fp_line
			(start 0.7874 0.4064)
			(end 0.7874 -0.4064)
			(stroke
				(width 0.1524)
				(type default)
			)
			(layer "B.SilkS")
		)
		(fp_line
			(start -0.7874 -0.4064)
			(end -0.7874 0.4064)
			(stroke
				(width 0.1524)
				(type default)
			)
			(layer "B.SilkS")
		)
		(fp_line
			(start 0.7874 -0.4064)
			(end -0.7874 -0.4064)
			(stroke
				(width 0.1524)
				(type default)
			)
			(layer "B.SilkS")
		)
		(fp_line
			(start -0.67945 0.3048)
			(end -0.120396 0.3048)
			(stroke
				(width 0.1)
				(type default)
			)
			(layer "B.Fab")
		)
		(fp_line
			(start -0.120396 0.3048)
			(end -0.120396 0.2794)
			(stroke
				(width 0.1)
				(type default)
			)
			(layer "B.Fab")
		)
		(fp_line
			(start 0.12065 0.3048)
			(end 0.67945 0.3048)
			(stroke
				(width 0.1)
				(type default)
			)
			(layer "B.Fab")
		)
		(fp_line
			(start 0.67945 0.3048)
			(end 0.67945 -0.305054)
			(stroke
				(width 0.1)
				(type default)
			)
			(layer "B.Fab")
		)
		(fp_line
			(start -0.120396 0.2794)
			(end 0.12065 0.2794)
			(stroke
				(width 0.1)
				(type default)
			)
			(layer "B.Fab")
		)
		(fp_line
			(start 0.12065 0.2794)
			(end 0.12065 0.3048)
			(stroke
				(width 0.1)
				(type default)
			)
			(layer "B.Fab")
		)
		(fp_line
			(start -0.12065 -0.2794)
			(end -0.12065 -0.3048)
			(stroke
				(width 0.1)
				(type default)
			)
			(layer "B.Fab")
		)
		(fp_line
			(start 0.12065 -0.2794)
			(end -0.12065 -0.2794)
			(stroke
				(width 0.1)
				(type default)
			)
			(layer "B.Fab")
		)
		(fp_line
			(start -0.67945 -0.3048)
			(end -0.67945 0.3048)
			(stroke
				(width 0.1)
				(type default)
			)
			(layer "B.Fab")
		)
		(fp_line
			(start -0.12065 -0.3048)
			(end -0.67945 -0.3048)
			(stroke
				(width 0.1)
				(type default)
			)
			(layer "B.Fab")
		)
		(fp_line
			(start 0.12065 -0.305054)
			(end 0.12065 -0.2794)
			(stroke
				(width 0.1)
				(type default)
			)
			(layer "B.Fab")
		)
		(fp_line
			(start 0.67945 -0.305054)
			(end 0.12065 -0.305054)
			(stroke
				(width 0.1)
				(type default)
			)
			(layer "B.Fab")
		)
		(pad "1" smd circle
			(at 0.40005 0 90)
			(size 0 0)
			(layers "B.Cu" "B.Mask" "B.Paste")
			(net "SPI2_CLK_BUF")
		)
		(pad "2" smd circle
			(at -0.40005 0 90)
			(size 0 0)
			(layers "B.Cu" "B.Mask" "B.Paste")
			(net "SPI_BIC1_CLK_R2")
		)
	)
	(footprint ""
		(layer "B.Cu")
		(at 117.071902 -283.818584 90)
		(property "Reference" "PR103"
			(at 0 0 90)
			(layer "B.SilkS")
			(hide yes)
			(effects
				(font
					(size 1.27 1.27)
				)
				(justify mirror)
			)
		)
		(property "Value" ""
			(at 0 0 90)
			(layer "B.Fab")
			(effects
				(font
					(size 1.27 1.27)
				)
				(justify mirror)
			)
		)
		(duplicate_pad_numbers_are_jumpers no)
		(fp_line
			(start 0.7874 -0.4064)
			(end -0.7874 -0.4064)
			(stroke
				(width 0.1524)
				(type default)
			)
			(layer "B.SilkS")
		)
		(fp_line
			(start -0.7874 -0.4064)
			(end -0.7874 0.4064)
			(stroke
				(width 0.1524)
				(type default)
			)
			(layer "B.SilkS")
		)
		(fp_line
			(start 0.7874 0.4064)
			(end 0.7874 -0.4064)
			(stroke
				(width 0.1524)
				(type default)
			)
			(layer "B.SilkS")
		)
		(fp_line
			(start -0.7874 0.4064)
			(end 0.7874 0.4064)
			(stroke
				(width 0.1524)
				(type default)
			)
			(layer "B.SilkS")
		)
		(fp_line
			(start 0.67945 -0.305054)
			(end 0.12065 -0.305054)
			(stroke
				(width 0.1)
				(type default)
			)
			(layer "B.Fab")
		)
		(fp_line
			(start 0.12065 -0.305054)
			(end 0.12065 -0.2794)
			(stroke
				(width 0.1)
				(type default)
			)
			(layer "B.Fab")
		)
		(fp_line
			(start -0.12065 -0.3048)
			(end -0.67945 -0.3048)
			(stroke
				(width 0.1)
				(type default)
			)
			(layer "B.Fab")
		)
		(fp_line
			(start -0.67945 -0.3048)
			(end -0.67945 0.3048)
			(stroke
				(width 0.1)
				(type default)
			)
			(layer "B.Fab")
		)
		(fp_line
			(start 0.12065 -0.2794)
			(end -0.12065 -0.2794)
			(stroke
				(width 0.1)
				(type default)
			)
			(layer "B.Fab")
		)
		(fp_line
			(start -0.12065 -0.2794)
			(end -0.12065 -0.3048)
			(stroke
				(width 0.1)
				(type default)
			)
			(layer "B.Fab")
		)
		(fp_line
			(start 0.12065 0.2794)
			(end 0.12065 0.3048)
			(stroke
				(width 0.1)
				(type default)
			)
			(layer "B.Fab")
		)
		(fp_line
			(start -0.120396 0.2794)
			(end 0.12065 0.2794)
			(stroke
				(width 0.1)
				(type default)
			)
			(layer "B.Fab")
		)
		(fp_line
			(start 0.67945 0.3048)
			(end 0.67945 -0.305054)
			(stroke
				(width 0.1)
				(type default)
			)
			(layer "B.Fab")
		)
		(fp_line
			(start 0.12065 0.3048)
			(end 0.67945 0.3048)
			(stroke
				(width 0.1)
				(type default)
			)
			(layer "B.Fab")
		)
		(fp_line
			(start -0.120396 0.3048)
			(end -0.120396 0.2794)
			(stroke
				(width 0.1)
				(type default)
			)
			(layer "B.Fab")
		)
		(fp_line
			(start -0.67945 0.3048)
			(end -0.120396 0.3048)
			(stroke
				(width 0.1)
				(type default)
			)
			(layer "B.Fab")
		)
		(pad "1" smd circle
			(at 0.40005 0 270)
			(size 0 0)
			(layers "B.Cu" "B.Mask" "B.Paste")
			(net "P0V8_PEX0_PVCC")
		)
		(pad "2" smd circle
			(at -0.40005 0 270)
			(size 0 0)
			(layers "B.Cu" "B.Mask" "B.Paste")
			(net "P0V8_PEX0_VCC2")
		)
	)
)
